FILE_TYPE = CONNECTIVITY;
{Allegro Design Entry HDL 16.6-p007 (v16-6-112F) 10/10/2012}
"PAGE_NUMBER" = 69;
0"NC";
1"GND\g";
2"TP_CPU1_UPI2_RSVD_CR14";
3"TP_CPU1_UPI2_RSVD_CC12";
4"TP_CPU1_UPI2_RSVD_CC10";
5"TP_CPU1_UPI2_RSVD_CE12";
6"TP_CPU1_UPI2_RSVD_CH11";
7"TP_CPU1_UPI2_RSVD_CF13";
8"TP_CPU1_UPI2_RSVD_CJ14";
9"TP_CPU1_UPI2_RSVD_CM13";
10"TP_CPU1_UPI2_RSVD_CA12";
11"TP_CPU1_UPI2_RSVD_CB11";
12"TP_CPU1_UPI2_RSVD_CD11";
13"TP_CPU1_UPI2_RSVD_CF11";
14"TP_CPU1_UPI2_RSVD_CG12";
15"TP_CPU1_UPI2_RSVD_CH13";
16"TP_CPU1_UPI2_RSVD_CK13";
17"TP_CPU1_UPI2_RSVD_CV13";
18"TP_CPU1_UPI2_RSVD_CW16";
19"TP_CPU1_UPI2_RSVD_DB15";
20"TP_CPU1_UPI2_RSVD_DD15";
21"TP_CPU1_UPI2_RSVD_DE16";
22"TP_CPU1_UPI2_RSVD_DF17";
23"TP_CPU1_UPI2_RSVD_DH17";
24"TP_CPU1_UPI2_RSVD_DJ18";
25"TP_CPU1_UPI2_RSVD_DJ20";
26"TP_CPU1_UPI2_RSVD_DK19";
27"TP_CPU1_UPI2_RSVD_DN20";
28"TP_CPU1_UPI2_RSVD_DP21";
29"TP_CPU1_UPI2_RSVD_CU14";
30"TP_CPU1_UPI2_RSVD_CW14";
31"TP_CPU1_UPI2_RSVD_DA16";
32"TP_CPU1_UPI2_RSVD_DC16";
33"TP_CPU1_UPI2_RSVD_DF15";
34"TP_CPU1_UPI2_RSVD_DD17";
35"TP_CPU1_UPI2_RSVD_DG18";
36"TP_CPU1_UPI2_RSVD_DK17";
37"TP_CPU1_UPI2_RSVD_DH19";
38"TP_CPU1_UPI2_RSVD_DG20";
39"TP_CPU1_UPI2_RSVD_DL20";
40"TP_CPU1_UPI2_RSVD_DM21";
41"TP_CPU1_UPI2_RSVD_DT21";
%"SKX_EXT_B"
"15","(-4275,2700)","0","chpset_lib","I1";
;
CDS_SEC"15"
LOCATION"U2D1"
PART_NUMBER"TBD"
MATERIAL"IC"
PACK_TYPE"BGA1"
SEC_TYPE"BGA1"
CDS_LIB"chpset_lib"
SEC"15"
CDS_LOCATION"U2D1";
"UPI2_TX_DP<0>"
$PN"DP21"10;
"UPI2_TX_DP<1>"
$PN"DN20"11;
"UPI2_TX_DP<2>"
$PN"DK19"12;
"UPI2_TX_DP<3>"
$PN"DJ20"13;
"UPI2_TX_DP<4>"
$PN"DJ18"14;
"UPI2_TX_DP<5>"
$PN"DH17"15;
"UPI2_TX_DP<6>"
$PN"DF17"16;
"UPI2_TX_DP<7>"
$PN"DE16"2;
"UPI2_TX_DP<8>"
$PN"DD15"17;
"UPI2_TX_DP<9>"
$PN"DB15"18;
"UPI2_TX_DP<10>"
$PN"CW16"19;
"UPI2_TX_DP<11>"
$PN"CV13"20;
"UPI2_TX_DP<12>"
$PN"CR14"21;
"UPI2_TX_DP<13>"
$PN"CK13"22;
"UPI2_TX_DP<14>"
$PN"CH13"23;
"UPI2_TX_DP<15>"
$PN"CG12"24;
"UPI2_TX_DP<16>"
$PN"CF11"25;
"UPI2_TX_DP<17>"
$PN"CD11"26;
"UPI2_TX_DP<18>"
$PN"CB11"27;
"UPI2_TX_DP<19>"
$PN"CA12"28;
"UPI2_TX_DN<0>"
$PN"DT21"3;
"UPI2_TX_DN<1>"
$PN"DM21"4;
"UPI2_TX_DN<2>"
$PN"DL20"5;
"UPI2_TX_DN<3>"
$PN"DG20"6;
"UPI2_TX_DN<4>"
$PN"DH19"7;
"UPI2_TX_DN<5>"
$PN"DK17"8;
"UPI2_TX_DN<6>"
$PN"DG18"9;
"UPI2_TX_DN<7>"
$PN"DD17"29;
"UPI2_TX_DN<8>"
$PN"DF15"30;
"UPI2_TX_DN<9>"
$PN"DC16"31;
"UPI2_TX_DN<10>"
$PN"DA16"32;
"UPI2_TX_DN<11>"
$PN"CW14"33;
"UPI2_TX_DN<12>"
$PN"CU14"34;
"UPI2_TX_DN<13>"
$PN"CM13"35;
"UPI2_TX_DN<14>"
$PN"CJ14"36;
"UPI2_TX_DN<15>"
$PN"CF13"37;
"UPI2_TX_DN<16>"
$PN"CH11"38;
"UPI2_TX_DN<17>"
$PN"CE12"39;
"UPI2_TX_DN<18>"
$PN"CC10"40;
"UPI2_TX_DN<19>"
$PN"CC12"41;
"UPI2_RX_DP<0>"
$PN"DG22"1;
"UPI2_RX_DP<1>"
$PN"DD21"1;
"UPI2_RX_DP<2>"
$PN"DA22"1;
"UPI2_RX_DP<3>"
$PN"DC20"1;
"UPI2_RX_DP<4>"
$PN"DB19"1;
"UPI2_RX_DP<5>"
$PN"CY19"1;
"UPI2_RX_DP<6>"
$PN"CU20"1;
"UPI2_RX_DP<7>"
$PN"CW18"1;
"UPI2_RX_DP<8>"
$PN"CR20"1;
"UPI2_RX_DP<9>"
$PN"CN18"1;
"UPI2_RX_DP<10>"
$PN"CP19"1;
"UPI2_RX_DP<11>"
$PN"CM21"1;
"UPI2_RX_DP<12>"
$PN"CJ16"1;
"UPI2_RX_DP<13>"
$PN"CK17"1;
"UPI2_RX_DP<14>"
$PN"CG16"1;
"UPI2_RX_DP<15>"
$PN"CF15"1;
"UPI2_RX_DP<16>"
$PN"CC14"1;
"UPI2_RX_DP<17>"
$PN"CD17"1;
"UPI2_RX_DP<18>"
$PN"BY15"1;
"UPI2_RX_DP<19>"
$PN"CA16"1;
"UPI2_RX_DN<0>"
$PN"DF23"1;
"UPI2_RX_DN<1>"
$PN"DE22"1;
"UPI2_RX_DN<2>"
$PN"DC22"1;
"UPI2_RX_DN<3>"
$PN"DB21"1;
"UPI2_RX_DN<4>"
$PN"DD19"1;
"UPI2_RX_DN<5>"
$PN"DA20"1;
"UPI2_RX_DN<6>"
$PN"CW20"1;
"UPI2_RX_DN<7>"
$PN"CV19"1;
"UPI2_RX_DN<8>"
$PN"CT21"1;
"UPI2_RX_DN<9>"
$PN"CR18"1;
"UPI2_RX_DN<10>"
$PN"CN20"1;
"UPI2_RX_DN<11>"
$PN"CP21"1;
"UPI2_RX_DN<12>"
$PN"CL16"1;
"UPI2_RX_DN<13>"
$PN"CJ18"1;
"UPI2_RX_DN<14>"
$PN"CH17"1;
"UPI2_RX_DN<15>"
$PN"CE16"1;
"UPI2_RX_DN<16>"
$PN"CD15"1;
"UPI2_RX_DN<17>"
$PN"CF17"1;
"UPI2_RX_DN<18>"
$PN"CB15"1;
"UPI2_RX_DN<19>"
$PN"BY17"1;
%"GND"
"1","(-6025,1475)","0","mstr_symbols","I2";
;
VOLTAGE"0.0V"
SIZE"1B"
CDS_LIB"mstr_symbols"
BODY_TYPE"PLUMBING"
HDL_POWER"GND";
"A\NAC"1;
END.
